(kicad_pcb
	(version 20260206)
	(generator "pcbnew")
	(generator_version "10.0")
	(general
		(thickness 1.6)
		(legacy_teardrops no)
	)
	(paper "A4")
	(title_block
		(title "Bryce Canyon_IOM_M2_16342-2_OCP.brd")
		(comment 1 "Bryce Canyon / footprints 762-768 of 1146")
	)
	(layers
		(0 "F.Cu" signal "TOP")
		(4 "In1.Cu" signal "L2GND")
		(6 "In2.Cu" signal "L3")
		(8 "In3.Cu" signal "L4VCC")
		(10 "In4.Cu" signal "L5VCC")
		(12 "In5.Cu" signal "L6")
		(14 "In6.Cu" signal "L7GND")
		(2 "B.Cu" signal "BOTTOM")
		(9 "F.Adhes" user "F.Adhesive")
		(11 "B.Adhes" user "B.Adhesive")
		(13 "F.Paste" user "Package Geometry/Pastemask Top")
		(15 "B.Paste" user "Package Geometry/Pastemask Bottom")
		(5 "F.SilkS" user "Ref Des/Silkscreen Top")
		(7 "B.SilkS" user "Ref Des/Silkscreen Bottom")
		(1 "F.Mask" user "Board Geometry/Soldermask Top")
		(3 "B.Mask" user "Board Geometry/Soldermask Bottom")
		(17 "Dwgs.User" user "User.Drawings")
		(19 "Cmts.User" user "User.Comments")
		(21 "Eco1.User" user "User.Eco1")
		(23 "Eco2.User" user "User.Eco2")
		(25 "Edge.Cuts" user "Board Geometry/Outline")
		(27 "Margin" user)
		(31 "F.CrtYd" user "Package Geometry/Place Bound Top")
		(29 "B.CrtYd" user "Package Geometry/Place Bound Bottom")
		(35 "F.Fab" user "Ref Des/Assembly Top")
		(33 "B.Fab" user "Ref Des/Assembly Bottom")
	)
	(footprint ""
		(layer "B.Cu")
		(at 60.2742 -138.5316)
		(property "Reference" "R272"
			(at 0 0 0)
			(layer "B.SilkS")
			(hide yes)
			(effects
				(font
					(size 1.27 1.27)
				)
				(justify mirror)
			)
		)
		(property "Value" "4K7R2F-GP"
			(at -0.064008 -3.993896 0)
			(unlocked yes)
			(layer "B.Fab")
			(hide yes)
			(effects
				(font
					(size 1.016 1.016)
					(thickness 0.1524)
				)
				(justify mirror)
			)
		)
		(property "Device Type" "R402H16"
			(at -0.064008 -5.517896 0)
			(unlocked yes)
			(layer "B.Fab")
			(hide yes)
			(effects
				(font
					(size 1.016 1.016)
					(thickness 0.1524)
				)
				(justify mirror)
			)
		)
		(duplicate_pad_numbers_are_jumpers no)
		(fp_line
			(start -0.508 -0.9398)
			(end 0.508 -0.9398)
			(stroke
				(width 0.1524)
				(type default)
			)
			(layer "B.SilkS")
		)
		(fp_line
			(start 0.508 -0.9398)
			(end 0.508 0.9398)
			(stroke
				(width 0.1524)
				(type default)
			)
			(layer "B.SilkS")
		)
		(fp_rect
			(start 0.508 0.9398)
			(end -0.508 -0.9398)
			(stroke
				(width 0)
				(type default)
			)
			(fill no)
			(layer "B.CrtYd")
		)
		(fp_rect
			(start 0.508 0.9398)
			(end -0.508 -0.9398)
			(stroke
				(width 0)
				(type default)
			)
			(fill no)
			(layer "B.Fab")
		)
		(pad "1" smd custom
			(at 0 -0.4445 180)
			(size 0.1397 0.1397)
			(layers "B.Cu" "B.Mask" "B.Paste")
			(net "SYS_PWR_LED")
			(options
				(clearance outline)
				(anchor circle)
			)
			(primitives
				(gr_poly
					(pts
						(arc
							(start -0.1778 0.2794)
							(mid -0.249642 0.249642)
							(end -0.2794 0.1778)
						)
						(arc
							(start -0.2794 -0.1778)
							(mid -0.249642 -0.249642)
							(end -0.1778 -0.2794)
						)
						(arc
							(start 0.1778 -0.2794)
							(mid 0.249642 -0.249642)
							(end 0.2794 -0.1778)
						)
						(arc
							(start 0.2794 0.1778)
							(mid 0.249642 0.249642)
							(end 0.1778 0.2794)
						)
					)
					(width 0)
					(fill yes)
				)
			)
		)
		(pad "2" smd custom
			(at 0 0.4445 180)
			(size 0.1397 0.1397)
			(layers "B.Cu" "B.Mask" "B.Paste")
			(net "P3V3_STBY")
			(options
				(clearance outline)
				(anchor circle)
			)
			(primitives
				(gr_poly
					(pts
						(arc
							(start -0.1778 0.2794)
							(mid -0.249642 0.249642)
							(end -0.2794 0.1778)
						)
						(arc
							(start -0.2794 -0.1778)
							(mid -0.249642 -0.249642)
							(end -0.1778 -0.2794)
						)
						(arc
							(start 0.1778 -0.2794)
							(mid 0.249642 -0.249642)
							(end 0.2794 -0.1778)
						)
						(arc
							(start 0.2794 0.1778)
							(mid 0.249642 0.249642)
							(end 0.1778 0.2794)
						)
					)
					(width 0)
					(fill yes)
				)
			)
		)
	)
	(footprint ""
		(layer "B.Cu")
		(at 61.75502 -143.949928 90)
		(property "Reference" "R153"
			(at 0 0 90)
			(layer "B.SilkS")
			(hide yes)
			(effects
				(font
					(size 1.27 1.27)
				)
				(justify mirror)
			)
		)
		(property "Value" "0R2J-2-GP"
			(at -0.064008 -3.993896 90)
			(unlocked yes)
			(layer "B.Fab")
			(hide yes)
			(effects
				(font
					(size 1.016 1.016)
					(thickness 0.1524)
				)
				(justify mirror)
			)
		)
		(property "Device Type" "R402H16"
			(at -0.064008 -5.517896 90)
			(unlocked yes)
			(layer "B.Fab")
			(hide yes)
			(effects
				(font
					(size 1.016 1.016)
					(thickness 0.1524)
				)
				(justify mirror)
			)
		)
		(duplicate_pad_numbers_are_jumpers no)
		(fp_line
			(start 0.508 -0.9398)
			(end 0.508 0.9398)
			(stroke
				(width 0.1524)
				(type default)
			)
			(layer "B.SilkS")
		)
		(fp_line
			(start -0.508 -0.9398)
			(end 0.508 -0.9398)
			(stroke
				(width 0.1524)
				(type default)
			)
			(layer "B.SilkS")
		)
		(fp_rect
			(start 0.508 0.9398)
			(end -0.508 -0.9398)
			(stroke
				(width 0)
				(type default)
			)
			(fill no)
			(layer "B.CrtYd")
		)
		(fp_rect
			(start 0.508 0.9398)
			(end -0.508 -0.9398)
			(stroke
				(width 0)
				(type default)
			)
			(fill no)
			(layer "B.Fab")
		)
		(pad "1" smd custom
			(at 0 -0.4445 270)
			(size 0.1397 0.1397)
			(layers "B.Cu" "B.Mask" "B.Paste")
			(net "BMC_SMB10_DAT")
			(options
				(clearance outline)
				(anchor circle)
			)
			(primitives
				(gr_poly
					(pts
						(arc
							(start -0.1778 0.2794)
							(mid -0.249642 0.249642)
							(end -0.2794 0.1778)
						)
						(arc
							(start -0.2794 -0.1778)
							(mid -0.249642 -0.249642)
							(end -0.1778 -0.2794)
						)
						(arc
							(start 0.1778 -0.2794)
							(mid 0.249642 -0.249642)
							(end 0.2794 -0.1778)
						)
						(arc
							(start 0.2794 0.1778)
							(mid 0.249642 0.249642)
							(end 0.1778 0.2794)
						)
					)
					(width 0)
					(fill yes)
				)
			)
		)
		(pad "2" smd custom
			(at 0 0.4445 270)
			(size 0.1397 0.1397)
			(layers "B.Cu" "B.Mask" "B.Paste")
			(net "I2C_EXP_LOC_SDA_OUT")
			(options
				(clearance outline)
				(anchor circle)
			)
			(primitives
				(gr_poly
					(pts
						(arc
							(start -0.1778 0.2794)
							(mid -0.249642 0.249642)
							(end -0.2794 0.1778)
						)
						(arc
							(start -0.2794 -0.1778)
							(mid -0.249642 -0.249642)
							(end -0.1778 -0.2794)
						)
						(arc
							(start 0.1778 -0.2794)
							(mid 0.249642 -0.249642)
							(end 0.2794 -0.1778)
						)
						(arc
							(start 0.2794 0.1778)
							(mid 0.249642 0.249642)
							(end 0.1778 0.2794)
						)
					)
					(width 0)
					(fill yes)
				)
			)
		)
	)
	(footprint ""
		(layer "B.Cu")
		(at 76.2 -151.9428 -90)
		(property "Reference" "U16"
			(at 0 0 90)
			(layer "B.SilkS")
			(hide yes)
			(effects
				(font
					(size 1.27 1.27)
				)
				(justify mirror)
			)
		)
		(property "Value" "NX3L1G66GW-GP"
			(at 2.3368 -8.6868 270)
			(unlocked yes)
			(layer "B.Fab")
			(hide yes)
			(effects
				(font
					(size 1.016 1.016)
					(thickness 0.1524)
				)
				(justify mirror)
			)
		)
		(property "Device Type" "SC70-5H44"
			(at 2.3114 -10.414 270)
			(unlocked yes)
			(layer "B.Fab")
			(hide yes)
			(effects
				(font
					(size 1.016 1.016)
					(thickness 0.1524)
				)
				(justify mirror)
			)
		)
		(duplicate_pad_numbers_are_jumpers no)
		(fp_line
			(start -1.27 1.7018)
			(end 1.27 1.7018)
			(stroke
				(width 0.1524)
				(type default)
			)
			(layer "B.SilkS")
		)
		(fp_line
			(start 1.27 1.7018)
			(end 1.27 -1.7018)
			(stroke
				(width 0.1524)
				(type default)
			)
			(layer "B.SilkS")
		)
		(fp_line
			(start -1.27 -1.7018)
			(end -1.27 1.7018)
			(stroke
				(width 0.1524)
				(type default)
			)
			(layer "B.SilkS")
		)
		(fp_line
			(start 1.27 -1.7018)
			(end -1.27 -1.7018)
			(stroke
				(width 0.1524)
				(type default)
			)
			(layer "B.SilkS")
		)
		(fp_line
			(start -1.3843 -1.8034)
			(end -1.3843 -1.1176)
			(stroke
				(width 0.3302)
				(type default)
			)
			(layer "B.SilkS")
		)
		(fp_line
			(start -0.6604 -1.8034)
			(end -1.3843 -1.8034)
			(stroke
				(width 0.3302)
				(type default)
			)
			(layer "B.SilkS")
		)
		(fp_rect
			(start 1.524 1.9558)
			(end -1.524 -1.9558)
			(stroke
				(width 0)
				(type default)
			)
			(fill no)
			(layer "B.CrtYd")
		)
		(fp_poly
			(pts
				(xy 1.524 -1.9558) (xy -1.524 -1.9558) (xy -1.524 1.9558) (xy 1.524 1.9558)
			)
			(stroke
				(width 0)
				(type default)
			)
			(fill no)
			(layer "B.Fab")
		)
		(pad "1" smd rect
			(at -0.65024 -0.8255 90)
			(size 0.4064 1.2192)
			(layers "B.Cu" "B.Mask" "B.Paste")
			(net "I2C_BMC_COMP_ALERT_N_R")
		)
		(pad "2" smd rect
			(at 0 -0.8255 90)
			(size 0.4064 1.2192)
			(layers "B.Cu" "B.Mask" "B.Paste")
			(net "I2C_COMP_ALERT_N")
		)
		(pad "3" smd rect
			(at 0.65024 -0.8255 90)
			(size 0.4064 1.2192)
			(layers "B.Cu" "B.Mask" "B.Paste")
			(net "GND")
		)
		(pad "4" smd rect
			(at 0.65024 0.8255 90)
			(size 0.4064 1.2192)
			(layers "B.Cu" "B.Mask" "B.Paste")
			(net "COMP_PWR_EN")
		)
		(pad "5" smd rect
			(at -0.65024 0.8255 90)
			(size 0.4064 1.2192)
			(layers "B.Cu" "B.Mask" "B.Paste")
			(net "P3V3_STBY")
		)
	)
	(footprint ""
		(layer "B.Cu")
		(at 91.245182 -171.118784 90)
		(property "Reference" "R418"
			(at 0 0 90)
			(layer "B.SilkS")
			(hide yes)
			(effects
				(font
					(size 1.27 1.27)
				)
				(justify mirror)
			)
		)
		(property "Value" "0R2J-2-GP"
			(at -0.064008 -3.993896 90)
			(unlocked yes)
			(layer "B.Fab")
			(hide yes)
			(effects
				(font
					(size 1.016 1.016)
					(thickness 0.1524)
				)
				(justify mirror)
			)
		)
		(property "Device Type" "R402H16"
			(at -0.064008 -5.517896 90)
			(unlocked yes)
			(layer "B.Fab")
			(hide yes)
			(effects
				(font
					(size 1.016 1.016)
					(thickness 0.1524)
				)
				(justify mirror)
			)
		)
		(duplicate_pad_numbers_are_jumpers no)
		(fp_line
			(start 0.508 -0.9398)
			(end 0.508 0.9398)
			(stroke
				(width 0.1524)
				(type default)
			)
			(layer "B.SilkS")
		)
		(fp_line
			(start -0.508 -0.9398)
			(end 0.508 -0.9398)
			(stroke
				(width 0.1524)
				(type default)
			)
			(layer "B.SilkS")
		)
		(fp_rect
			(start 0.508 0.9398)
			(end -0.508 -0.9398)
			(stroke
				(width 0)
				(type default)
			)
			(fill no)
			(layer "B.CrtYd")
		)
		(fp_rect
			(start 0.508 0.9398)
			(end -0.508 -0.9398)
			(stroke
				(width 0)
				(type default)
			)
			(fill no)
			(layer "B.Fab")
		)
		(pad "1" smd custom
			(at 0 -0.4445 270)
			(size 0.1397 0.1397)
			(layers "B.Cu" "B.Mask" "B.Paste")
			(net "UART_COMP_R_TX")
			(options
				(clearance outline)
				(anchor circle)
			)
			(primitives
				(gr_poly
					(pts
						(arc
							(start -0.1778 0.2794)
							(mid -0.249642 0.249642)
							(end -0.2794 0.1778)
						)
						(arc
							(start -0.2794 -0.1778)
							(mid -0.249642 -0.249642)
							(end -0.1778 -0.2794)
						)
						(arc
							(start 0.1778 -0.2794)
							(mid 0.249642 -0.249642)
							(end 0.2794 -0.1778)
						)
						(arc
							(start 0.2794 0.1778)
							(mid 0.249642 0.249642)
							(end 0.1778 0.2794)
						)
					)
					(width 0)
					(fill yes)
				)
			)
		)
		(pad "2" smd custom
			(at 0 0.4445 270)
			(size 0.1397 0.1397)
			(layers "B.Cu" "B.Mask" "B.Paste")
			(net "UART_COMP_TX")
			(options
				(clearance outline)
				(anchor circle)
			)
			(primitives
				(gr_poly
					(pts
						(arc
							(start -0.1778 0.2794)
							(mid -0.249642 0.249642)
							(end -0.2794 0.1778)
						)
						(arc
							(start -0.2794 -0.1778)
							(mid -0.249642 -0.249642)
							(end -0.1778 -0.2794)
						)
						(arc
							(start 0.1778 -0.2794)
							(mid 0.249642 -0.249642)
							(end 0.2794 -0.1778)
						)
						(arc
							(start 0.2794 0.1778)
							(mid 0.249642 0.249642)
							(end 0.1778 0.2794)
						)
					)
					(width 0)
					(fill yes)
				)
			)
		)
	)
	(footprint ""
		(layer "B.Cu")
		(at 91.68892 -149.526244)
		(property "Reference" "C14"
			(at 0 0 0)
			(layer "B.SilkS")
			(hide yes)
			(effects
				(font
					(size 1.27 1.27)
				)
				(justify mirror)
			)
		)
		(property "Value" "SC1KP50V2KX-1GP"
			(at -1.1811 -2.7051 0)
			(unlocked yes)
			(layer "B.Fab")
			(hide yes)
			(effects
				(font
					(size 1.016 1.016)
					(thickness 0.1524)
				)
				(justify mirror)
			)
		)
		(property "Device Type" "C402H22"
			(at -1.1811 -4.2291 0)
			(unlocked yes)
			(layer "B.Fab")
			(hide yes)
			(effects
				(font
					(size 1.016 1.016)
					(thickness 0.1524)
				)
				(justify mirror)
			)
		)
		(duplicate_pad_numbers_are_jumpers no)
		(fp_rect
			(start 0.4318 0.9525)
			(end -0.4318 -0.9525)
			(stroke
				(width 0)
				(type default)
			)
			(fill no)
			(layer "B.CrtYd")
		)
		(fp_rect
			(start 0.4318 0.9525)
			(end -0.4318 -0.9525)
			(stroke
				(width 0)
				(type default)
			)
			(fill no)
			(layer "B.Fab")
		)
		(pad "1" smd custom
			(at 0 -0.4445 180)
			(size 0.1524 0.1524)
			(layers "B.Cu" "B.Mask" "B.Paste")
			(net "USB_OCS_N1")
			(options
				(clearance outline)
				(anchor circle)
			)
			(primitives
				(gr_poly
					(pts
						(arc
							(start 0.3048 0.2032)
							(mid 0.275042 0.275042)
							(end 0.2032 0.3048)
						)
						(arc
							(start -0.2032 0.3048)
							(mid -0.275042 0.275042)
							(end -0.3048 0.2032)
						)
						(arc
							(start -0.3048 -0.2032)
							(mid -0.275042 -0.275042)
							(end -0.2032 -0.3048)
						)
						(arc
							(start 0.2032 -0.3048)
							(mid 0.275042 -0.275042)
							(end 0.3048 -0.2032)
						)
					)
					(width 0)
					(fill yes)
				)
			)
		)
		(pad "2" smd custom
			(at 0 0.4445 180)
			(size 0.1524 0.1524)
			(layers "B.Cu" "B.Mask" "B.Paste")
			(net "GND")
			(options
				(clearance outline)
				(anchor circle)
			)
			(primitives
				(gr_poly
					(pts
						(arc
							(start 0.3048 0.2032)
							(mid 0.275042 0.275042)
							(end 0.2032 0.3048)
						)
						(arc
							(start -0.2032 0.3048)
							(mid -0.275042 0.275042)
							(end -0.3048 0.2032)
						)
						(arc
							(start -0.3048 -0.2032)
							(mid -0.275042 -0.275042)
							(end -0.2032 -0.3048)
						)
						(arc
							(start 0.2032 -0.3048)
							(mid 0.275042 -0.275042)
							(end 0.3048 -0.2032)
						)
					)
					(width 0)
					(fill yes)
				)
			)
		)
	)
	(footprint ""
		(layer "B.Cu")
		(at 45.144436 -157.25648 -90)
		(property "Reference" "R697"
			(at 0 0 90)
			(layer "B.SilkS")
			(hide yes)
			(effects
				(font
					(size 1.27 1.27)
				)
				(justify mirror)
			)
		)
		(property "Value" "4K7R2F-GP"
			(at -0.064008 -3.993896 270)
			(unlocked yes)
			(layer "B.Fab")
			(hide yes)
			(effects
				(font
					(size 1.016 1.016)
					(thickness 0.1524)
				)
				(justify mirror)
			)
		)
		(property "Device Type" "R402H16"
			(at -0.064008 -5.517896 270)
			(unlocked yes)
			(layer "B.Fab")
			(hide yes)
			(effects
				(font
					(size 1.016 1.016)
					(thickness 0.1524)
				)
				(justify mirror)
			)
		)
		(duplicate_pad_numbers_are_jumpers no)
		(fp_line
			(start -0.508 -0.9398)
			(end 0.508 -0.9398)
			(stroke
				(width 0.1524)
				(type default)
			)
			(layer "B.SilkS")
		)
		(fp_line
			(start 0.508 -0.9398)
			(end 0.508 0.9398)
			(stroke
				(width 0.1524)
				(type default)
			)
			(layer "B.SilkS")
		)
		(fp_rect
			(start 0.508 0.9398)
			(end -0.508 -0.9398)
			(stroke
				(width 0)
				(type default)
			)
			(fill no)
			(layer "B.CrtYd")
		)
		(fp_rect
			(start 0.508 0.9398)
			(end -0.508 -0.9398)
			(stroke
				(width 0)
				(type default)
			)
			(fill no)
			(layer "B.Fab")
		)
		(pad "1" smd custom
			(at 0 -0.4445 90)
			(size 0.1397 0.1397)
			(layers "B.Cu" "B.Mask" "B.Paste")
			(net "P3V3_STBY")
			(options
				(clearance outline)
				(anchor circle)
			)
			(primitives
				(gr_poly
					(pts
						(arc
							(start -0.1778 0.2794)
							(mid -0.249642 0.249642)
							(end -0.2794 0.1778)
						)
						(arc
							(start -0.2794 -0.1778)
							(mid -0.249642 -0.249642)
							(end -0.1778 -0.2794)
						)
						(arc
							(start 0.1778 -0.2794)
							(mid 0.249642 -0.249642)
							(end 0.2794 -0.1778)
						)
						(arc
							(start 0.2794 0.1778)
							(mid 0.249642 0.249642)
							(end 0.1778 0.2794)
						)
					)
					(width 0)
					(fill yes)
				)
			)
		)
		(pad "2" smd custom
			(at 0 0.4445 90)
			(size 0.1397 0.1397)
			(layers "B.Cu" "B.Mask" "B.Paste")
			(net "PCIE_WAKE_N")
			(options
				(clearance outline)
				(anchor circle)
			)
			(primitives
				(gr_poly
					(pts
						(arc
							(start -0.1778 0.2794)
							(mid -0.249642 0.249642)
							(end -0.2794 0.1778)
						)
						(arc
							(start -0.2794 -0.1778)
							(mid -0.249642 -0.249642)
							(end -0.1778 -0.2794)
						)
						(arc
							(start 0.1778 -0.2794)
							(mid 0.249642 -0.249642)
							(end 0.2794 -0.1778)
						)
						(arc
							(start 0.2794 0.1778)
							(mid 0.249642 0.249642)
							(end 0.1778 0.2794)
						)
					)
					(width 0)
					(fill yes)
				)
			)
		)
	)
	(footprint ""
		(layer "B.Cu")
		(at 22.011386 -131.007358 180)
		(property "Reference" "R261"
			(at 0 0 0)
			(layer "B.SilkS")
			(hide yes)
			(effects
				(font
					(size 1.27 1.27)
				)
				(justify mirror)
			)
		)
		(property "Value" "120R2F-GP"
			(at -0.064008 -3.993896 180)
			(unlocked yes)
			(layer "B.Fab")
			(hide yes)
			(effects
				(font
					(size 1.016 1.016)
					(thickness 0.1524)
				)
				(justify mirror)
			)
		)
		(property "Device Type" "R402H16"
			(at -0.064008 -5.517896 180)
			(unlocked yes)
			(layer "B.Fab")
			(hide yes)
			(effects
				(font
					(size 1.016 1.016)
					(thickness 0.1524)
				)
				(justify mirror)
			)
		)
		(duplicate_pad_numbers_are_jumpers no)
		(fp_line
			(start 0.508 -0.9398)
			(end 0.508 0.9398)
			(stroke
				(width 0.1524)
				(type default)
			)
			(layer "B.SilkS")
		)
		(fp_line
			(start -0.508 -0.9398)
			(end 0.508 -0.9398)
			(stroke
				(width 0.1524)
				(type default)
			)
			(layer "B.SilkS")
		)
		(fp_rect
			(start 0.508 0.9398)
			(end -0.508 -0.9398)
			(stroke
				(width 0)
				(type default)
			)
			(fill no)
			(layer "B.CrtYd")
		)
		(fp_rect
			(start 0.508 0.9398)
			(end -0.508 -0.9398)
			(stroke
				(width 0)
				(type default)
			)
			(fill no)
			(layer "B.Fab")
		)
		(pad "1" smd custom
			(at 0 -0.4445)
			(size 0.1397 0.1397)
			(layers "B.Cu" "B.Mask" "B.Paste")
			(net "MEMA_13")
			(options
				(clearance outline)
				(anchor circle)
			)
			(primitives
				(gr_poly
					(pts
						(arc
							(start -0.1778 0.2794)
							(mid -0.249642 0.249642)
							(end -0.2794 0.1778)
						)
						(arc
							(start -0.2794 -0.1778)
							(mid -0.249642 -0.249642)
							(end -0.1778 -0.2794)
						)
						(arc
							(start 0.1778 -0.2794)
							(mid 0.249642 -0.249642)
							(end 0.2794 -0.1778)
						)
						(arc
							(start 0.2794 0.1778)
							(mid 0.249642 0.249642)
							(end 0.1778 0.2794)
						)
					)
					(width 0)
					(fill yes)
				)
			)
		)
		(pad "2" smd custom
			(at 0 0.4445)
			(size 0.1397 0.1397)
			(layers "B.Cu" "B.Mask" "B.Paste")
			(net "P1V2_STBY")
			(options
				(clearance outline)
				(anchor circle)
			)
			(primitives
				(gr_poly
					(pts
						(arc
							(start -0.1778 0.2794)
							(mid -0.249642 0.249642)
							(end -0.2794 0.1778)
						)
						(arc
							(start -0.2794 -0.1778)
							(mid -0.249642 -0.249642)
							(end -0.1778 -0.2794)
						)
						(arc
							(start 0.1778 -0.2794)
							(mid 0.249642 -0.249642)
							(end 0.2794 -0.1778)
						)
						(arc
							(start 0.2794 0.1778)
							(mid 0.249642 0.249642)
							(end 0.1778 0.2794)
						)
					)
					(width 0)
					(fill yes)
				)
			)
		)
	)
)
